(kicad_pcb
	(version 20260206)
	(generator "pcbnew")
	(generator_version "10.0")
	(general
		(thickness 1.6)
		(legacy_teardrops no)
	)
	(paper "A4")
	(title_block
		(title "01162023_DA0F0TEBIF0_F0T_Expander_BD_F_brd_V02_OCP.brd")
		(comment 1 "Grand Teton / footprints 166-172 of 9728")
	)
	(layers
		(0 "F.Cu" signal "TOP")
		(4 "In1.Cu" signal "GND")
		(6 "In2.Cu" signal "VCC")
		(8 "In3.Cu" signal "VCC1")
		(10 "In4.Cu" signal "GND1")
		(12 "In5.Cu" signal "IN1")
		(14 "In6.Cu" signal "GND2")
		(16 "In7.Cu" signal "IN2")
		(18 "In8.Cu" signal "GND3")
		(20 "In9.Cu" signal "IN3")
		(22 "In10.Cu" signal "GND4")
		(24 "In11.Cu" signal "IN4")
		(26 "In12.Cu" signal "GND5")
		(28 "In13.Cu" signal "IN5")
		(30 "In14.Cu" signal "GND6")
		(32 "In15.Cu" signal "IN6")
		(34 "In16.Cu" signal "GND7")
		(2 "B.Cu" signal "BOTTOM")
		(9 "F.Adhes" user "F.Adhesive")
		(11 "B.Adhes" user "B.Adhesive")
		(13 "F.Paste" user "Package Geometry/Pastemask Top")
		(15 "B.Paste" user "Package Geometry/Pastemask Bottom")
		(5 "F.SilkS" user "Ref Des/Silkscreen Top")
		(7 "B.SilkS" user "Ref Des/Silkscreen Bottom")
		(1 "F.Mask" user "Board Geometry/Soldermask Top")
		(3 "B.Mask" user "Board Geometry/Soldermask Bottom")
		(17 "Dwgs.User" user "User.Drawings")
		(19 "Cmts.User" user "User.Comments")
		(21 "Eco1.User" user "User.Eco1")
		(23 "Eco2.User" user "User.Eco2")
		(25 "Edge.Cuts" user "Board Geometry/Outline")
		(27 "Margin" user)
		(31 "F.CrtYd" user "Package Geometry/Place Bound Top")
		(29 "B.CrtYd" user "Package Geometry/Place Bound Bottom")
		(35 "F.Fab" user "Ref Des/Assembly Top")
		(33 "B.Fab" user "Ref Des/Assembly Bottom")
	)
	(footprint ""
		(layer "F.Cu")
		(at 97.498408 -66.32194 -90)
		(property "Reference" "PC654"
			(at 0 0 270)
			(layer "F.SilkS")
			(hide yes)
			(effects
				(font
					(size 1.27 1.27)
				)
			)
		)
		(property "Value" ""
			(at 0 0 270)
			(layer "F.Fab")
			(effects
				(font
					(size 1.27 1.27)
				)
			)
		)
		(duplicate_pad_numbers_are_jumpers no)
		(fp_line
			(start -0.7874 0.4064)
			(end -0.7874 -0.4064)
			(stroke
				(width 0.1524)
				(type default)
			)
			(layer "F.SilkS")
		)
		(fp_line
			(start 0.7874 0.4064)
			(end -0.7874 0.4064)
			(stroke
				(width 0.1524)
				(type default)
			)
			(layer "F.SilkS")
		)
		(fp_line
			(start -0.7874 -0.4064)
			(end 0.7874 -0.4064)
			(stroke
				(width 0.1524)
				(type default)
			)
			(layer "F.SilkS")
		)
		(fp_line
			(start 0.7874 -0.4064)
			(end 0.7874 0.4064)
			(stroke
				(width 0.1524)
				(type default)
			)
			(layer "F.SilkS")
		)
		(fp_line
			(start -0.67945 0.3048)
			(end -0.67945 -0.305054)
			(stroke
				(width 0.1)
				(type default)
			)
			(layer "F.Fab")
		)
		(fp_line
			(start -0.12065 0.3048)
			(end -0.67945 0.3048)
			(stroke
				(width 0.1)
				(type default)
			)
			(layer "F.Fab")
		)
		(fp_line
			(start 0.120396 0.3048)
			(end 0.120396 0.2794)
			(stroke
				(width 0.1)
				(type default)
			)
			(layer "F.Fab")
		)
		(fp_line
			(start 0.67945 0.3048)
			(end 0.120396 0.3048)
			(stroke
				(width 0.1)
				(type default)
			)
			(layer "F.Fab")
		)
		(fp_line
			(start -0.12065 0.2794)
			(end -0.12065 0.3048)
			(stroke
				(width 0.1)
				(type default)
			)
			(layer "F.Fab")
		)
		(fp_line
			(start 0.120396 0.2794)
			(end -0.12065 0.2794)
			(stroke
				(width 0.1)
				(type default)
			)
			(layer "F.Fab")
		)
		(fp_line
			(start -0.12065 -0.2794)
			(end 0.12065 -0.2794)
			(stroke
				(width 0.1)
				(type default)
			)
			(layer "F.Fab")
		)
		(fp_line
			(start 0.12065 -0.2794)
			(end 0.12065 -0.3048)
			(stroke
				(width 0.1)
				(type default)
			)
			(layer "F.Fab")
		)
		(fp_line
			(start 0.12065 -0.3048)
			(end 0.67945 -0.3048)
			(stroke
				(width 0.1)
				(type default)
			)
			(layer "F.Fab")
		)
		(fp_line
			(start 0.67945 -0.3048)
			(end 0.67945 0.3048)
			(stroke
				(width 0.1)
				(type default)
			)
			(layer "F.Fab")
		)
		(fp_line
			(start -0.67945 -0.305054)
			(end -0.12065 -0.305054)
			(stroke
				(width 0.1)
				(type default)
			)
			(layer "F.Fab")
		)
		(fp_line
			(start -0.12065 -0.305054)
			(end -0.12065 -0.2794)
			(stroke
				(width 0.1)
				(type default)
			)
			(layer "F.Fab")
		)
		(pad "1" smd circle
			(at -0.40005 0 270)
			(size 0 0)
			(layers "F.Cu" "F.Mask" "F.Paste")
			(net "P12V_SSD3_CO_GATE")
		)
		(pad "2" smd circle
			(at 0.40005 0 270)
			(size 0 0)
			(layers "F.Cu" "F.Mask" "F.Paste")
			(net "GND")
		)
	)
	(footprint ""
		(layer "F.Cu")
		(at 142.343886 -43.85691)
		(property "Reference" "R553"
			(at 0 0 0)
			(layer "F.SilkS")
			(hide yes)
			(effects
				(font
					(size 1.27 1.27)
				)
			)
		)
		(property "Value" ""
			(at 0 0 0)
			(layer "F.Fab")
			(effects
				(font
					(size 1.27 1.27)
				)
			)
		)
		(duplicate_pad_numbers_are_jumpers no)
		(fp_line
			(start -0.7874 -0.4064)
			(end 0.7874 -0.4064)
			(stroke
				(width 0.1524)
				(type default)
			)
			(layer "F.SilkS")
		)
		(fp_line
			(start -0.7874 0.4064)
			(end -0.7874 -0.4064)
			(stroke
				(width 0.1524)
				(type default)
			)
			(layer "F.SilkS")
		)
		(fp_line
			(start 0.7874 -0.4064)
			(end 0.7874 0.4064)
			(stroke
				(width 0.1524)
				(type default)
			)
			(layer "F.SilkS")
		)
		(fp_line
			(start 0.7874 0.4064)
			(end -0.7874 0.4064)
			(stroke
				(width 0.1524)
				(type default)
			)
			(layer "F.SilkS")
		)
		(fp_line
			(start -0.67945 -0.305054)
			(end -0.12065 -0.305054)
			(stroke
				(width 0.1)
				(type default)
			)
			(layer "F.Fab")
		)
		(fp_line
			(start -0.67945 0.3048)
			(end -0.67945 -0.305054)
			(stroke
				(width 0.1)
				(type default)
			)
			(layer "F.Fab")
		)
		(fp_line
			(start -0.12065 -0.305054)
			(end -0.12065 -0.2794)
			(stroke
				(width 0.1)
				(type default)
			)
			(layer "F.Fab")
		)
		(fp_line
			(start -0.12065 -0.2794)
			(end 0.12065 -0.2794)
			(stroke
				(width 0.1)
				(type default)
			)
			(layer "F.Fab")
		)
		(fp_line
			(start -0.12065 0.2794)
			(end -0.12065 0.3048)
			(stroke
				(width 0.1)
				(type default)
			)
			(layer "F.Fab")
		)
		(fp_line
			(start -0.12065 0.3048)
			(end -0.67945 0.3048)
			(stroke
				(width 0.1)
				(type default)
			)
			(layer "F.Fab")
		)
		(fp_line
			(start 0.120396 0.2794)
			(end -0.12065 0.2794)
			(stroke
				(width 0.1)
				(type default)
			)
			(layer "F.Fab")
		)
		(fp_line
			(start 0.120396 0.3048)
			(end 0.120396 0.2794)
			(stroke
				(width 0.1)
				(type default)
			)
			(layer "F.Fab")
		)
		(fp_line
			(start 0.12065 -0.3048)
			(end 0.67945 -0.3048)
			(stroke
				(width 0.1)
				(type default)
			)
			(layer "F.Fab")
		)
		(fp_line
			(start 0.12065 -0.2794)
			(end 0.12065 -0.3048)
			(stroke
				(width 0.1)
				(type default)
			)
			(layer "F.Fab")
		)
		(fp_line
			(start 0.67945 -0.3048)
			(end 0.67945 0.3048)
			(stroke
				(width 0.1)
				(type default)
			)
			(layer "F.Fab")
		)
		(fp_line
			(start 0.67945 0.3048)
			(end 0.120396 0.3048)
			(stroke
				(width 0.1)
				(type default)
			)
			(layer "F.Fab")
		)
		(pad "1" smd circle
			(at -0.40005 0)
			(size 0 0)
			(layers "F.Cu" "F.Mask" "F.Paste")
			(net "SSD4_ADC_A1")
		)
		(pad "2" smd circle
			(at 0.40005 0)
			(size 0 0)
			(layers "F.Cu" "F.Mask" "F.Paste")
			(net "GND")
		)
	)
	(footprint ""
		(layer "F.Cu")
		(at 204.591158 -77.563472)
		(property "Reference" "R4337"
			(at 0 0 0)
			(layer "F.SilkS")
			(hide yes)
			(effects
				(font
					(size 1.27 1.27)
				)
			)
		)
		(property "Value" ""
			(at 0 0 0)
			(layer "F.Fab")
			(effects
				(font
					(size 1.27 1.27)
				)
			)
		)
		(duplicate_pad_numbers_are_jumpers no)
		(fp_line
			(start -0.7874 -0.4064)
			(end 0.7874 -0.4064)
			(stroke
				(width 0.1524)
				(type default)
			)
			(layer "F.SilkS")
		)
		(fp_line
			(start -0.7874 0.4064)
			(end -0.7874 -0.4064)
			(stroke
				(width 0.1524)
				(type default)
			)
			(layer "F.SilkS")
		)
		(fp_line
			(start 0.7874 -0.4064)
			(end 0.7874 0.4064)
			(stroke
				(width 0.1524)
				(type default)
			)
			(layer "F.SilkS")
		)
		(fp_line
			(start 0.7874 0.4064)
			(end -0.7874 0.4064)
			(stroke
				(width 0.1524)
				(type default)
			)
			(layer "F.SilkS")
		)
		(fp_line
			(start -0.67945 -0.305054)
			(end -0.12065 -0.305054)
			(stroke
				(width 0.1)
				(type default)
			)
			(layer "F.Fab")
		)
		(fp_line
			(start -0.67945 0.3048)
			(end -0.67945 -0.305054)
			(stroke
				(width 0.1)
				(type default)
			)
			(layer "F.Fab")
		)
		(fp_line
			(start -0.12065 -0.305054)
			(end -0.12065 -0.2794)
			(stroke
				(width 0.1)
				(type default)
			)
			(layer "F.Fab")
		)
		(fp_line
			(start -0.12065 -0.2794)
			(end 0.12065 -0.2794)
			(stroke
				(width 0.1)
				(type default)
			)
			(layer "F.Fab")
		)
		(fp_line
			(start -0.12065 0.2794)
			(end -0.12065 0.3048)
			(stroke
				(width 0.1)
				(type default)
			)
			(layer "F.Fab")
		)
		(fp_line
			(start -0.12065 0.3048)
			(end -0.67945 0.3048)
			(stroke
				(width 0.1)
				(type default)
			)
			(layer "F.Fab")
		)
		(fp_line
			(start 0.120396 0.2794)
			(end -0.12065 0.2794)
			(stroke
				(width 0.1)
				(type default)
			)
			(layer "F.Fab")
		)
		(fp_line
			(start 0.120396 0.3048)
			(end 0.120396 0.2794)
			(stroke
				(width 0.1)
				(type default)
			)
			(layer "F.Fab")
		)
		(fp_line
			(start 0.12065 -0.3048)
			(end 0.67945 -0.3048)
			(stroke
				(width 0.1)
				(type default)
			)
			(layer "F.Fab")
		)
		(fp_line
			(start 0.12065 -0.2794)
			(end 0.12065 -0.3048)
			(stroke
				(width 0.1)
				(type default)
			)
			(layer "F.Fab")
		)
		(fp_line
			(start 0.67945 -0.3048)
			(end 0.67945 0.3048)
			(stroke
				(width 0.1)
				(type default)
			)
			(layer "F.Fab")
		)
		(fp_line
			(start 0.67945 0.3048)
			(end 0.120396 0.3048)
			(stroke
				(width 0.1)
				(type default)
			)
			(layer "F.Fab")
		)
		(pad "1" smd circle
			(at -0.40005 0)
			(size 0 0)
			(layers "F.Cu" "F.Mask" "F.Paste")
			(net "P3V3_AUX")
		)
		(pad "2" smd circle
			(at 0.40005 0)
			(size 0 0)
			(layers "F.Cu" "F.Mask" "F.Paste")
			(net "SSD7_LED_R")
		)
	)
	(footprint ""
		(layer "F.Cu")
		(at 381.127 -201.168)
		(property "Reference" "R4700"
			(at 0 0 0)
			(layer "F.SilkS")
			(hide yes)
			(effects
				(font
					(size 1.27 1.27)
				)
			)
		)
		(property "Value" ""
			(at 0 0 0)
			(layer "F.Fab")
			(effects
				(font
					(size 1.27 1.27)
				)
			)
		)
		(duplicate_pad_numbers_are_jumpers no)
		(fp_line
			(start -0.7874 -0.4064)
			(end 0.7874 -0.4064)
			(stroke
				(width 0.1524)
				(type default)
			)
			(layer "F.SilkS")
		)
		(fp_line
			(start -0.7874 0.4064)
			(end -0.7874 -0.4064)
			(stroke
				(width 0.1524)
				(type default)
			)
			(layer "F.SilkS")
		)
		(fp_line
			(start 0.7874 -0.4064)
			(end 0.7874 0.4064)
			(stroke
				(width 0.1524)
				(type default)
			)
			(layer "F.SilkS")
		)
		(fp_line
			(start 0.7874 0.4064)
			(end -0.7874 0.4064)
			(stroke
				(width 0.1524)
				(type default)
			)
			(layer "F.SilkS")
		)
		(fp_line
			(start -0.67945 -0.305054)
			(end -0.12065 -0.305054)
			(stroke
				(width 0.1)
				(type default)
			)
			(layer "F.Fab")
		)
		(fp_line
			(start -0.67945 0.3048)
			(end -0.67945 -0.305054)
			(stroke
				(width 0.1)
				(type default)
			)
			(layer "F.Fab")
		)
		(fp_line
			(start -0.12065 -0.305054)
			(end -0.12065 -0.2794)
			(stroke
				(width 0.1)
				(type default)
			)
			(layer "F.Fab")
		)
		(fp_line
			(start -0.12065 -0.2794)
			(end 0.12065 -0.2794)
			(stroke
				(width 0.1)
				(type default)
			)
			(layer "F.Fab")
		)
		(fp_line
			(start -0.12065 0.2794)
			(end -0.12065 0.3048)
			(stroke
				(width 0.1)
				(type default)
			)
			(layer "F.Fab")
		)
		(fp_line
			(start -0.12065 0.3048)
			(end -0.67945 0.3048)
			(stroke
				(width 0.1)
				(type default)
			)
			(layer "F.Fab")
		)
		(fp_line
			(start 0.120396 0.2794)
			(end -0.12065 0.2794)
			(stroke
				(width 0.1)
				(type default)
			)
			(layer "F.Fab")
		)
		(fp_line
			(start 0.120396 0.3048)
			(end 0.120396 0.2794)
			(stroke
				(width 0.1)
				(type default)
			)
			(layer "F.Fab")
		)
		(fp_line
			(start 0.12065 -0.3048)
			(end 0.67945 -0.3048)
			(stroke
				(width 0.1)
				(type default)
			)
			(layer "F.Fab")
		)
		(fp_line
			(start 0.12065 -0.2794)
			(end 0.12065 -0.3048)
			(stroke
				(width 0.1)
				(type default)
			)
			(layer "F.Fab")
		)
		(fp_line
			(start 0.67945 -0.3048)
			(end 0.67945 0.3048)
			(stroke
				(width 0.1)
				(type default)
			)
			(layer "F.Fab")
		)
		(fp_line
			(start 0.67945 0.3048)
			(end 0.120396 0.3048)
			(stroke
				(width 0.1)
				(type default)
			)
			(layer "F.Fab")
		)
		(pad "1" smd circle
			(at -0.40005 0)
			(size 0 0)
			(layers "F.Cu" "F.Mask" "F.Paste")
			(net "GND")
		)
		(pad "2" smd circle
			(at 0.40005 0)
			(size 0 0)
			(layers "F.Cu" "F.Mask" "F.Paste")
			(net "PCA9555_0_PEX1_A0")
		)
	)
	(footprint ""
		(layer "F.Cu")
		(at 258.623562 -214.162386)
		(property "Reference" "C2849"
			(at 0 0 0)
			(layer "F.SilkS")
			(hide yes)
			(effects
				(font
					(size 1.27 1.27)
				)
			)
		)
		(property "Value" ""
			(at 0 0 0)
			(layer "F.Fab")
			(effects
				(font
					(size 1.27 1.27)
				)
			)
		)
		(duplicate_pad_numbers_are_jumpers no)
		(fp_line
			(start -1.524 -0.762)
			(end 1.524 -0.762)
			(stroke
				(width 0.1524)
				(type default)
			)
			(layer "F.SilkS")
		)
		(fp_line
			(start -1.524 0.762)
			(end -1.524 -0.762)
			(stroke
				(width 0.1524)
				(type default)
			)
			(layer "F.SilkS")
		)
		(fp_line
			(start 1.524 -0.762)
			(end 1.524 0.762)
			(stroke
				(width 0.1524)
				(type default)
			)
			(layer "F.SilkS")
		)
		(fp_line
			(start 1.524 0.762)
			(end -1.524 0.762)
			(stroke
				(width 0.1524)
				(type default)
			)
			(layer "F.SilkS")
		)
		(fp_line
			(start -1.1049 -0.724916)
			(end -1.1049 0.724916)
			(stroke
				(width 0.1)
				(type default)
			)
			(layer "F.Fab")
		)
		(fp_line
			(start -1.1049 0.724916)
			(end 1.1049 0.724916)
			(stroke
				(width 0.1)
				(type default)
			)
			(layer "F.Fab")
		)
		(fp_line
			(start 1.1049 -0.724916)
			(end -1.1049 -0.724916)
			(stroke
				(width 0.1)
				(type default)
			)
			(layer "F.Fab")
		)
		(fp_line
			(start 1.1049 0.724916)
			(end 1.1049 -0.724916)
			(stroke
				(width 0.1)
				(type default)
			)
			(layer "F.Fab")
		)
		(pad "1" smd rect
			(at -0.889 0 180)
			(size 1.016 1.27)
			(layers "F.Cu" "F.Mask" "F.Paste")
			(net "P3V3_AUX")
		)
		(pad "2" smd rect
			(at 0.889 0 180)
			(size 1.016 1.27)
			(layers "F.Cu" "F.Mask" "F.Paste")
			(net "GND")
		)
	)
	(footprint ""
		(layer "F.Cu")
		(at 374.567958 -52.035456 180)
		(property "Reference" "R870"
			(at 0 0 180)
			(layer "F.SilkS")
			(hide yes)
			(effects
				(font
					(size 1.27 1.27)
				)
			)
		)
		(property "Value" ""
			(at 0 0 180)
			(layer "F.Fab")
			(effects
				(font
					(size 1.27 1.27)
				)
			)
		)
		(duplicate_pad_numbers_are_jumpers no)
		(fp_line
			(start 0.7874 0.4064)
			(end -0.7874 0.4064)
			(stroke
				(width 0.1524)
				(type default)
			)
			(layer "F.SilkS")
		)
		(fp_line
			(start 0.7874 -0.4064)
			(end 0.7874 0.4064)
			(stroke
				(width 0.1524)
				(type default)
			)
			(layer "F.SilkS")
		)
		(fp_line
			(start -0.7874 0.4064)
			(end -0.7874 -0.4064)
			(stroke
				(width 0.1524)
				(type default)
			)
			(layer "F.SilkS")
		)
		(fp_line
			(start -0.7874 -0.4064)
			(end 0.7874 -0.4064)
			(stroke
				(width 0.1524)
				(type default)
			)
			(layer "F.SilkS")
		)
		(fp_line
			(start 0.67945 0.3048)
			(end 0.120396 0.3048)
			(stroke
				(width 0.1)
				(type default)
			)
			(layer "F.Fab")
		)
		(fp_line
			(start 0.67945 -0.3048)
			(end 0.67945 0.3048)
			(stroke
				(width 0.1)
				(type default)
			)
			(layer "F.Fab")
		)
		(fp_line
			(start 0.12065 -0.2794)
			(end 0.12065 -0.3048)
			(stroke
				(width 0.1)
				(type default)
			)
			(layer "F.Fab")
		)
		(fp_line
			(start 0.12065 -0.3048)
			(end 0.67945 -0.3048)
			(stroke
				(width 0.1)
				(type default)
			)
			(layer "F.Fab")
		)
		(fp_line
			(start 0.120396 0.3048)
			(end 0.120396 0.2794)
			(stroke
				(width 0.1)
				(type default)
			)
			(layer "F.Fab")
		)
		(fp_line
			(start 0.120396 0.2794)
			(end -0.12065 0.2794)
			(stroke
				(width 0.1)
				(type default)
			)
			(layer "F.Fab")
		)
		(fp_line
			(start -0.12065 0.3048)
			(end -0.67945 0.3048)
			(stroke
				(width 0.1)
				(type default)
			)
			(layer "F.Fab")
		)
		(fp_line
			(start -0.12065 0.2794)
			(end -0.12065 0.3048)
			(stroke
				(width 0.1)
				(type default)
			)
			(layer "F.Fab")
		)
		(fp_line
			(start -0.12065 -0.2794)
			(end 0.12065 -0.2794)
			(stroke
				(width 0.1)
				(type default)
			)
			(layer "F.Fab")
		)
		(fp_line
			(start -0.12065 -0.305054)
			(end -0.12065 -0.2794)
			(stroke
				(width 0.1)
				(type default)
			)
			(layer "F.Fab")
		)
		(fp_line
			(start -0.67945 0.3048)
			(end -0.67945 -0.305054)
			(stroke
				(width 0.1)
				(type default)
			)
			(layer "F.Fab")
		)
		(fp_line
			(start -0.67945 -0.305054)
			(end -0.12065 -0.305054)
			(stroke
				(width 0.1)
				(type default)
			)
			(layer "F.Fab")
		)
		(pad "1" smd circle
			(at -0.40005 0 180)
			(size 0 0)
			(layers "F.Cu" "F.Mask" "F.Paste")
			(net "P3V3_AUX")
		)
		(pad "2" smd circle
			(at 0.40005 0 180)
			(size 0 0)
			(layers "F.Cu" "F.Mask" "F.Paste")
			(net "PWRGD_P12V_SSD12")
		)
	)
	(footprint ""
		(layer "F.Cu")
		(at 356.676706 -392.284712 90)
		(property "Reference" "C4455"
			(at 0 0 90)
			(layer "F.SilkS")
			(hide yes)
			(effects
				(font
					(size 1.27 1.27)
				)
			)
		)
		(property "Value" ""
			(at 0 0 90)
			(layer "F.Fab")
			(effects
				(font
					(size 1.27 1.27)
				)
			)
		)
		(duplicate_pad_numbers_are_jumpers no)
		(fp_line
			(start 0.299974 -0.150114)
			(end 0.299974 0.150114)
			(stroke
				(width 0.1)
				(type default)
			)
			(layer "F.Fab")
		)
		(fp_line
			(start -0.299974 -0.150114)
			(end 0.299974 -0.150114)
			(stroke
				(width 0.1)
				(type default)
			)
			(layer "F.Fab")
		)
		(fp_line
			(start 0.299974 0.150114)
			(end -0.299974 0.150114)
			(stroke
				(width 0.1)
				(type default)
			)
			(layer "F.Fab")
		)
		(fp_line
			(start -0.299974 0.150114)
			(end -0.299974 -0.150114)
			(stroke
				(width 0.1)
				(type default)
			)
			(layer "F.Fab")
		)
		(pad "1" smd rect
			(at -0.2667 0 90)
			(size 0.3048 0.381)
			(layers "F.Cu" "F.Mask" "F.Paste")
			(net "MB_3V3IO_RSVD1_ISO")
		)
		(pad "2" smd rect
			(at 0.2667 0 90)
			(size 0.3048 0.381)
			(layers "F.Cu" "F.Mask" "F.Paste")
			(net "GND")
		)
	)
)
